(kicad_pcb
	(version 20260206)
	(generator "pcbnew")
	(generator_version "10.0")
	(general
		(thickness 1.6)
		(legacy_teardrops no)
	)
	(paper "A4")
	(title_block
		(title "Bryce Canyon_SCC_16316-1_OCP.brd")
		(comment 1 "Bryce Canyon / footprints 54-62 of 1561")
	)
	(layers
		(0 "F.Cu" signal "TOP")
		(4 "In1.Cu" signal "L2GND")
		(6 "In2.Cu" signal "L3")
		(8 "In3.Cu" signal "L4VCC")
		(10 "In4.Cu" signal "L5VCC")
		(12 "In5.Cu" signal "L6")
		(14 "In6.Cu" signal "L7GND")
		(2 "B.Cu" signal "BOTTOM")
		(9 "F.Adhes" user "F.Adhesive")
		(11 "B.Adhes" user "B.Adhesive")
		(13 "F.Paste" user "Package Geometry/Pastemask Top")
		(15 "B.Paste" user "Package Geometry/Pastemask Bottom")
		(5 "F.SilkS" user "Ref Des/Silkscreen Top")
		(7 "B.SilkS" user "Ref Des/Silkscreen Bottom")
		(1 "F.Mask" user "Board Geometry/Soldermask Top")
		(3 "B.Mask" user "Board Geometry/Soldermask Bottom")
		(17 "Dwgs.User" user "User.Drawings")
		(19 "Cmts.User" user "User.Comments")
		(21 "Eco1.User" user "User.Eco1")
		(23 "Eco2.User" user "User.Eco2")
		(25 "Edge.Cuts" user "Board Geometry/Outline")
		(27 "Margin" user)
		(31 "F.CrtYd" user "Package Geometry/Place Bound Top")
		(29 "B.CrtYd" user "Package Geometry/Place Bound Bottom")
		(35 "F.Fab" user "Ref Des/Assembly Top")
		(33 "B.Fab" user "Ref Des/Assembly Bottom")
	)
	(footprint ""
		(layer "F.Cu")
		(at 18.6944 -81.7118 -90)
		(property "Reference" "C529"
			(at 0 0 270)
			(layer "F.SilkS")
			(hide yes)
			(effects
				(font
					(size 1.27 1.27)
				)
			)
		)
		(property "Value" "SCD01U25V2KX-3GP"
			(at 1.1811 -2.7051 270)
			(unlocked yes)
			(layer "F.Fab")
			(hide yes)
			(effects
				(font
					(size 1.016 1.016)
					(thickness 0.1524)
				)
			)
		)
		(property "Device Type" "C402H22"
			(at 1.1811 -4.2291 270)
			(unlocked yes)
			(layer "F.Fab")
			(hide yes)
			(effects
				(font
					(size 1.016 1.016)
					(thickness 0.1524)
				)
			)
		)
		(duplicate_pad_numbers_are_jumpers no)
		(fp_rect
			(start -0.4318 0.9525)
			(end 0.4318 -0.9525)
			(stroke
				(width 0)
				(type default)
			)
			(fill no)
			(layer "F.CrtYd")
		)
		(fp_rect
			(start -0.4318 0.9525)
			(end 0.4318 -0.9525)
			(stroke
				(width 0)
				(type default)
			)
			(fill no)
			(layer "F.Fab")
		)
		(pad "1" smd custom
			(at 0 -0.4445 270)
			(size 0.1524 0.1524)
			(layers "F.Cu" "F.Mask" "F.Paste")
			(net "GND")
			(options
				(clearance outline)
				(anchor circle)
			)
			(primitives
				(gr_poly
					(pts
						(arc
							(start 0.3048 -0.2032)
							(mid 0.275042 -0.275042)
							(end 0.2032 -0.3048)
						)
						(arc
							(start -0.2032 -0.3048)
							(mid -0.275042 -0.275042)
							(end -0.3048 -0.2032)
						)
						(arc
							(start -0.3048 0.2032)
							(mid -0.275042 0.275042)
							(end -0.2032 0.3048)
						)
						(arc
							(start 0.2032 0.3048)
							(mid 0.275042 0.275042)
							(end 0.3048 0.2032)
						)
					)
					(width 0)
					(fill yes)
				)
			)
		)
		(pad "2" smd custom
			(at 0 0.4445 270)
			(size 0.1524 0.1524)
			(layers "F.Cu" "F.Mask" "F.Paste")
			(net "P3V3")
			(options
				(clearance outline)
				(anchor circle)
			)
			(primitives
				(gr_poly
					(pts
						(arc
							(start 0.3048 -0.2032)
							(mid 0.275042 -0.275042)
							(end 0.2032 -0.3048)
						)
						(arc
							(start -0.2032 -0.3048)
							(mid -0.275042 -0.275042)
							(end -0.3048 -0.2032)
						)
						(arc
							(start -0.3048 0.2032)
							(mid -0.275042 0.275042)
							(end -0.2032 0.3048)
						)
						(arc
							(start 0.2032 0.3048)
							(mid 0.275042 0.275042)
							(end 0.3048 0.2032)
						)
					)
					(width 0)
					(fill yes)
				)
			)
		)
	)
	(footprint ""
		(layer "F.Cu")
		(at 53.467 -51.4604 180)
		(property "Reference" "R479"
			(at 0 0 180)
			(layer "F.SilkS")
			(hide yes)
			(effects
				(font
					(size 1.27 1.27)
				)
			)
		)
		(property "Value" "1R5F-1-GP"
			(at 0 -8.9535 180)
			(unlocked yes)
			(layer "F.Fab")
			(hide yes)
			(effects
				(font
					(size 1.27 1.016)
					(thickness 0.1524)
				)
			)
		)
		(property "Device Type" "R805H24"
			(at 0 -10.6299 180)
			(unlocked yes)
			(layer "F.Fab")
			(hide yes)
			(effects
				(font
					(size 1.27 1.016)
					(thickness 0.1524)
				)
			)
		)
		(duplicate_pad_numbers_are_jumpers no)
		(fp_line
			(start 0.889 1.7018)
			(end 0.889 -0.508)
			(stroke
				(width 0.1524)
				(type default)
			)
			(layer "F.SilkS")
		)
		(fp_line
			(start 0.889 -1.7018)
			(end 0.889 -0.381)
			(stroke
				(width 0.1524)
				(type default)
			)
			(layer "F.SilkS")
		)
		(fp_line
			(start 0.889 -1.7018)
			(end -0.889 -1.7018)
			(stroke
				(width 0.1524)
				(type default)
			)
			(layer "F.SilkS")
		)
		(fp_line
			(start -0.889 1.7018)
			(end 0.889 1.7018)
			(stroke
				(width 0.1524)
				(type default)
			)
			(layer "F.SilkS")
		)
		(fp_line
			(start -0.889 0.0762)
			(end -0.889 1.7018)
			(stroke
				(width 0.1524)
				(type default)
			)
			(layer "F.SilkS")
		)
		(fp_line
			(start -0.889 -1.7018)
			(end -0.889 0.2794)
			(stroke
				(width 0.1524)
				(type default)
			)
			(layer "F.SilkS")
		)
		(fp_poly
			(pts
				(xy 0.9652 -1.778) (xy 0.9652 1.778) (xy -0.9652 1.778) (xy -0.9652 -1.778)
			)
			(stroke
				(width 0)
				(type default)
			)
			(fill no)
			(layer "F.CrtYd")
		)
		(fp_rect
			(start -0.9652 1.778)
			(end 0.9652 -1.778)
			(stroke
				(width 0)
				(type default)
			)
			(fill no)
			(layer "F.Fab")
		)
		(pad "1" smd rect
			(at 0 -0.9652 180)
			(size 1.397 1.143)
			(layers "F.Cu" "F.Mask" "F.Paste")
			(net "P0V9_VSW")
		)
		(pad "2" smd rect
			(at 0 0.9652 180)
			(size 1.397 1.143)
			(layers "F.Cu" "F.Mask" "F.Paste")
			(net "P0V9_SNB")
		)
	)
	(footprint ""
		(layer "F.Cu")
		(at 194.5132 -31.9532 -90)
		(property "Reference" "TP101"
			(at 0 0 270)
			(layer "F.SilkS")
			(hide yes)
			(effects
				(font
					(size 1.27 1.27)
				)
			)
		)
		(property "Value" "TPAD28-2-GP"
			(at -0.0127 -1.6637 270)
			(unlocked yes)
			(layer "F.Fab")
			(hide yes)
			(effects
				(font
					(size 1.016 1.016)
					(thickness 0.1524)
				)
			)
		)
		(property "Device Type" "TPAD28"
			(at -0.0127 -3.1877 270)
			(unlocked yes)
			(layer "F.Fab")
			(hide yes)
			(effects
				(font
					(size 1.016 1.016)
					(thickness 0.1524)
				)
			)
		)
		(duplicate_pad_numbers_are_jumpers no)
		(fp_poly
			(pts
				(arc
					(start 0 -0.3556)
					(mid 0 0.3556)
					(end 0 -0.3556)
				)
			)
			(stroke
				(width 0)
				(type default)
			)
			(fill no)
			(layer "F.CrtYd")
		)
		(fp_poly
			(pts
				(arc
					(start 0 -0.6096)
					(mid 0 0.6096)
					(end 0 -0.6096)
				)
			)
			(stroke
				(width 0)
				(type default)
			)
			(fill no)
			(layer "F.Fab")
		)
		(pad "1" smd circle
			(at 0 0 270)
			(size 0.7112 0.7112)
			(layers "F.Cu" "F.Mask" "F.Paste")
			(net "IOC_GPIO_39")
		)
	)
	(footprint ""
		(layer "F.Cu")
		(at 152.980898 -82.970624 -90)
		(property "Reference" "R327"
			(at 0 0 270)
			(layer "F.SilkS")
			(hide yes)
			(effects
				(font
					(size 1.27 1.27)
				)
			)
		)
		(property "Value" "0R2J-2-GP"
			(at 0.064008 -3.993896 270)
			(unlocked yes)
			(layer "F.Fab")
			(hide yes)
			(effects
				(font
					(size 1.016 1.016)
					(thickness 0.1524)
				)
			)
		)
		(property "Device Type" "R402H16"
			(at 0.064008 -5.517896 270)
			(unlocked yes)
			(layer "F.Fab")
			(hide yes)
			(effects
				(font
					(size 1.016 1.016)
					(thickness 0.1524)
				)
			)
		)
		(duplicate_pad_numbers_are_jumpers no)
		(fp_line
			(start -0.508 -0.9398)
			(end -0.508 0.9398)
			(stroke
				(width 0.1524)
				(type default)
			)
			(layer "F.SilkS")
		)
		(fp_line
			(start 0.508 -0.9398)
			(end -0.508 -0.9398)
			(stroke
				(width 0.1524)
				(type default)
			)
			(layer "F.SilkS")
		)
		(fp_rect
			(start -0.508 0.9398)
			(end 0.508 -0.9398)
			(stroke
				(width 0)
				(type default)
			)
			(fill no)
			(layer "F.CrtYd")
		)
		(fp_rect
			(start -0.508 0.9398)
			(end 0.508 -0.9398)
			(stroke
				(width 0)
				(type default)
			)
			(fill no)
			(layer "F.Fab")
		)
		(pad "1" smd custom
			(at 0 -0.4445 270)
			(size 0.1397 0.1397)
			(layers "F.Cu" "F.Mask" "F.Paste")
			(net "VOL_SEN1_SCL")
			(options
				(clearance outline)
				(anchor circle)
			)
			(primitives
				(gr_poly
					(pts
						(arc
							(start -0.1778 -0.2794)
							(mid -0.249642 -0.249642)
							(end -0.2794 -0.1778)
						)
						(arc
							(start -0.2794 0.1778)
							(mid -0.249642 0.249642)
							(end -0.1778 0.2794)
						)
						(arc
							(start 0.1778 0.2794)
							(mid 0.249642 0.249642)
							(end 0.2794 0.1778)
						)
						(arc
							(start 0.2794 -0.1778)
							(mid 0.249642 -0.249642)
							(end 0.1778 -0.2794)
						)
					)
					(width 0)
					(fill yes)
				)
			)
		)
		(pad "2" smd custom
			(at 0 0.4445 270)
			(size 0.1397 0.1397)
			(layers "F.Cu" "F.Mask" "F.Paste")
			(net "I2C_SCC_SCL2")
			(options
				(clearance outline)
				(anchor circle)
			)
			(primitives
				(gr_poly
					(pts
						(arc
							(start -0.1778 -0.2794)
							(mid -0.249642 -0.249642)
							(end -0.2794 -0.1778)
						)
						(arc
							(start -0.2794 0.1778)
							(mid -0.249642 0.249642)
							(end -0.1778 0.2794)
						)
						(arc
							(start 0.1778 0.2794)
							(mid 0.249642 0.249642)
							(end 0.2794 0.1778)
						)
						(arc
							(start 0.2794 -0.1778)
							(mid 0.249642 -0.249642)
							(end 0.1778 -0.2794)
						)
					)
					(width 0)
					(fill yes)
				)
			)
		)
	)
	(footprint ""
		(layer "F.Cu")
		(at 187.651644 -58.476642)
		(property "Reference" "R214"
			(at 0 0 0)
			(layer "F.SilkS")
			(hide yes)
			(effects
				(font
					(size 1.27 1.27)
				)
			)
		)
		(property "Value" "10KR2F-2-GP"
			(at 0.064008 -3.993896 0)
			(unlocked yes)
			(layer "F.Fab")
			(hide yes)
			(effects
				(font
					(size 1.016 1.016)
					(thickness 0.1524)
				)
			)
		)
		(property "Device Type" "R402H16"
			(at 0.064008 -5.517896 0)
			(unlocked yes)
			(layer "F.Fab")
			(hide yes)
			(effects
				(font
					(size 1.016 1.016)
					(thickness 0.1524)
				)
			)
		)
		(duplicate_pad_numbers_are_jumpers no)
		(fp_line
			(start -0.508 -0.9398)
			(end -0.508 0.9398)
			(stroke
				(width 0.1524)
				(type default)
			)
			(layer "F.SilkS")
		)
		(fp_line
			(start 0.508 -0.9398)
			(end -0.508 -0.9398)
			(stroke
				(width 0.1524)
				(type default)
			)
			(layer "F.SilkS")
		)
		(fp_rect
			(start -0.508 0.9398)
			(end 0.508 -0.9398)
			(stroke
				(width 0)
				(type default)
			)
			(fill no)
			(layer "F.CrtYd")
		)
		(fp_rect
			(start -0.508 0.9398)
			(end 0.508 -0.9398)
			(stroke
				(width 0)
				(type default)
			)
			(fill no)
			(layer "F.Fab")
		)
		(pad "1" smd custom
			(at 0 -0.4445)
			(size 0.1397 0.1397)
			(layers "F.Cu" "F.Mask" "F.Paste")
			(net "P1V8_C")
			(options
				(clearance outline)
				(anchor circle)
			)
			(primitives
				(gr_poly
					(pts
						(arc
							(start -0.1778 -0.2794)
							(mid -0.249642 -0.249642)
							(end -0.2794 -0.1778)
						)
						(arc
							(start -0.2794 0.1778)
							(mid -0.249642 0.249642)
							(end -0.1778 0.2794)
						)
						(arc
							(start 0.1778 0.2794)
							(mid 0.249642 0.249642)
							(end 0.2794 0.1778)
						)
						(arc
							(start 0.2794 -0.1778)
							(mid 0.249642 -0.249642)
							(end 0.1778 -0.2794)
						)
					)
					(width 0)
					(fill yes)
				)
			)
		)
		(pad "2" smd custom
			(at 0 0.4445)
			(size 0.1397 0.1397)
			(layers "F.Cu" "F.Mask" "F.Paste")
			(net "XM_ADDR_4")
			(options
				(clearance outline)
				(anchor circle)
			)
			(primitives
				(gr_poly
					(pts
						(arc
							(start -0.1778 -0.2794)
							(mid -0.249642 -0.249642)
							(end -0.2794 -0.1778)
						)
						(arc
							(start -0.2794 0.1778)
							(mid -0.249642 0.249642)
							(end -0.1778 0.2794)
						)
						(arc
							(start 0.1778 0.2794)
							(mid 0.249642 0.249642)
							(end 0.2794 0.1778)
						)
						(arc
							(start 0.2794 -0.1778)
							(mid 0.249642 -0.249642)
							(end 0.1778 -0.2794)
						)
					)
					(width 0)
					(fill yes)
				)
			)
		)
	)
	(footprint ""
		(layer "F.Cu")
		(at 115.7986 -86.6394)
		(property "Reference" "TP45"
			(at 0 0 0)
			(layer "F.SilkS")
			(hide yes)
			(effects
				(font
					(size 1.27 1.27)
				)
			)
		)
		(property "Value" "TPAD28-2-GP"
			(at -0.0127 -1.6637 0)
			(unlocked yes)
			(layer "F.Fab")
			(hide yes)
			(effects
				(font
					(size 1.016 1.016)
					(thickness 0.1524)
				)
			)
		)
		(property "Device Type" "TPAD28"
			(at -0.0127 -3.1877 0)
			(unlocked yes)
			(layer "F.Fab")
			(hide yes)
			(effects
				(font
					(size 1.016 1.016)
					(thickness 0.1524)
				)
			)
		)
		(duplicate_pad_numbers_are_jumpers no)
		(fp_poly
			(pts
				(arc
					(start 0.3556 0)
					(mid -0.3556 0)
					(end 0.3556 0)
				)
			)
			(stroke
				(width 0)
				(type default)
			)
			(fill no)
			(layer "F.CrtYd")
		)
		(fp_poly
			(pts
				(arc
					(start 0.6096 0)
					(mid -0.6096 0)
					(end 0.6096 0)
				)
			)
			(stroke
				(width 0)
				(type default)
			)
			(fill no)
			(layer "F.Fab")
		)
		(pad "1" smd circle
			(at 0 0)
			(size 0.7112 0.7112)
			(layers "F.Cu" "F.Mask" "F.Paste")
			(net "EXP_XM_ADDR_25")
		)
	)
	(footprint ""
		(layer "F.Cu")
		(at 159.512 -42.291 90)
		(property "Reference" "C334"
			(at 0 0 90)
			(layer "F.SilkS")
			(hide yes)
			(effects
				(font
					(size 1.27 1.27)
				)
			)
		)
		(property "Value" "SC15P50V2JN-2-GP"
			(at 1.1811 -2.7051 90)
			(unlocked yes)
			(layer "F.Fab")
			(hide yes)
			(effects
				(font
					(size 1.016 1.016)
					(thickness 0.1524)
				)
			)
		)
		(property "Device Type" "C402H22"
			(at 1.1811 -4.2291 90)
			(unlocked yes)
			(layer "F.Fab")
			(hide yes)
			(effects
				(font
					(size 1.016 1.016)
					(thickness 0.1524)
				)
			)
		)
		(duplicate_pad_numbers_are_jumpers no)
		(fp_rect
			(start -0.4318 0.9525)
			(end 0.4318 -0.9525)
			(stroke
				(width 0)
				(type default)
			)
			(fill no)
			(layer "F.CrtYd")
		)
		(fp_rect
			(start -0.4318 0.9525)
			(end 0.4318 -0.9525)
			(stroke
				(width 0)
				(type default)
			)
			(fill no)
			(layer "F.Fab")
		)
		(pad "1" smd custom
			(at 0 -0.4445 90)
			(size 0.1524 0.1524)
			(layers "F.Cu" "F.Mask" "F.Paste")
			(net "IOC_REF_CLK_P")
			(options
				(clearance outline)
				(anchor circle)
			)
			(primitives
				(gr_poly
					(pts
						(arc
							(start 0.3048 -0.2032)
							(mid 0.275042 -0.275042)
							(end 0.2032 -0.3048)
						)
						(arc
							(start -0.2032 -0.3048)
							(mid -0.275042 -0.275042)
							(end -0.3048 -0.2032)
						)
						(arc
							(start -0.3048 0.2032)
							(mid -0.275042 0.275042)
							(end -0.2032 0.3048)
						)
						(arc
							(start 0.2032 0.3048)
							(mid 0.275042 0.275042)
							(end 0.3048 0.2032)
						)
					)
					(width 0)
					(fill yes)
				)
			)
		)
		(pad "2" smd custom
			(at 0 0.4445 90)
			(size 0.1524 0.1524)
			(layers "F.Cu" "F.Mask" "F.Paste")
			(net "GND")
			(options
				(clearance outline)
				(anchor circle)
			)
			(primitives
				(gr_poly
					(pts
						(arc
							(start 0.3048 -0.2032)
							(mid 0.275042 -0.275042)
							(end 0.2032 -0.3048)
						)
						(arc
							(start -0.2032 -0.3048)
							(mid -0.275042 -0.275042)
							(end -0.3048 -0.2032)
						)
						(arc
							(start -0.3048 0.2032)
							(mid -0.275042 0.275042)
							(end -0.2032 0.3048)
						)
						(arc
							(start 0.2032 0.3048)
							(mid 0.275042 0.275042)
							(end 0.3048 0.2032)
						)
					)
					(width 0)
					(fill yes)
				)
			)
		)
	)
	(footprint ""
		(layer "F.Cu")
		(at 60.73775 -123.205494)
		(property "Reference" "R509"
			(at 0 0 0)
			(layer "F.SilkS")
			(hide yes)
			(effects
				(font
					(size 1.27 1.27)
				)
			)
		)
		(property "Value" "0R5J-5-GP"
			(at 0 -8.9535 0)
			(unlocked yes)
			(layer "F.Fab")
			(hide yes)
			(effects
				(font
					(size 1.27 1.016)
					(thickness 0.1524)
				)
			)
		)
		(property "Device Type" "R805H24"
			(at 0 -10.6299 0)
			(unlocked yes)
			(layer "F.Fab")
			(hide yes)
			(effects
				(font
					(size 1.27 1.016)
					(thickness 0.1524)
				)
			)
		)
		(duplicate_pad_numbers_are_jumpers no)
		(fp_line
			(start -0.889 -1.7018)
			(end -0.889 0.2794)
			(stroke
				(width 0.1524)
				(type default)
			)
			(layer "F.SilkS")
		)
		(fp_line
			(start -0.889 0.0762)
			(end -0.889 1.7018)
			(stroke
				(width 0.1524)
				(type default)
			)
			(layer "F.SilkS")
		)
		(fp_line
			(start -0.889 1.7018)
			(end 0.889 1.7018)
			(stroke
				(width 0.1524)
				(type default)
			)
			(layer "F.SilkS")
		)
		(fp_line
			(start 0.889 -1.7018)
			(end -0.889 -1.7018)
			(stroke
				(width 0.1524)
				(type default)
			)
			(layer "F.SilkS")
		)
		(fp_line
			(start 0.889 -1.7018)
			(end 0.889 -0.381)
			(stroke
				(width 0.1524)
				(type default)
			)
			(layer "F.SilkS")
		)
		(fp_line
			(start 0.889 1.7018)
			(end 0.889 -0.508)
			(stroke
				(width 0.1524)
				(type default)
			)
			(layer "F.SilkS")
		)
		(fp_poly
			(pts
				(xy 0.9652 -1.778) (xy 0.9652 1.778) (xy -0.9652 1.778) (xy -0.9652 -1.778)
			)
			(stroke
				(width 0)
				(type default)
			)
			(fill no)
			(layer "F.CrtYd")
		)
		(fp_rect
			(start -0.9652 1.778)
			(end 0.9652 -1.778)
			(stroke
				(width 0)
				(type default)
			)
			(fill no)
			(layer "F.Fab")
		)
		(pad "1" smd rect
			(at 0 -0.9652)
			(size 1.397 1.143)
			(layers "F.Cu" "F.Mask" "F.Paste")
			(net "P3V3")
		)
		(pad "2" smd rect
			(at 0 0.9652)
			(size 1.397 1.143)
			(layers "F.Cu" "F.Mask" "F.Paste")
			(net "P3V3_OUT")
		)
	)
	(footprint ""
		(layer "F.Cu")
		(at 192.8241 -35.433 -90)
		(property "Reference" "R184"
			(at 0 0 270)
			(layer "F.SilkS")
			(hide yes)
			(effects
				(font
					(size 1.27 1.27)
				)
			)
		)
		(property "Value" "2K2R2F-GP"
			(at 0.064008 -3.993896 270)
			(unlocked yes)
			(layer "F.Fab")
			(hide yes)
			(effects
				(font
					(size 1.016 1.016)
					(thickness 0.1524)
				)
			)
		)
		(property "Device Type" "R402H16"
			(at 0.064008 -5.517896 270)
			(unlocked yes)
			(layer "F.Fab")
			(hide yes)
			(effects
				(font
					(size 1.016 1.016)
					(thickness 0.1524)
				)
			)
		)
		(duplicate_pad_numbers_are_jumpers no)
		(fp_line
			(start -0.508 -0.9398)
			(end -0.508 0.9398)
			(stroke
				(width 0.1524)
				(type default)
			)
			(layer "F.SilkS")
		)
		(fp_line
			(start 0.508 -0.9398)
			(end -0.508 -0.9398)
			(stroke
				(width 0.1524)
				(type default)
			)
			(layer "F.SilkS")
		)
		(fp_rect
			(start -0.508 0.9398)
			(end 0.508 -0.9398)
			(stroke
				(width 0)
				(type default)
			)
			(fill no)
			(layer "F.CrtYd")
		)
		(fp_rect
			(start -0.508 0.9398)
			(end 0.508 -0.9398)
			(stroke
				(width 0)
				(type default)
			)
			(fill no)
			(layer "F.Fab")
		)
		(pad "1" smd custom
			(at 0 -0.4445 270)
			(size 0.1397 0.1397)
			(layers "F.Cu" "F.Mask" "F.Paste")
			(net "P1V8_C")
			(options
				(clearance outline)
				(anchor circle)
			)
			(primitives
				(gr_poly
					(pts
						(arc
							(start -0.1778 -0.2794)
							(mid -0.249642 -0.249642)
							(end -0.2794 -0.1778)
						)
						(arc
							(start -0.2794 0.1778)
							(mid -0.249642 0.249642)
							(end -0.1778 0.2794)
						)
						(arc
							(start 0.1778 0.2794)
							(mid 0.249642 0.249642)
							(end 0.2794 0.1778)
						)
						(arc
							(start 0.2794 -0.1778)
							(mid 0.249642 -0.249642)
							(end 0.1778 -0.2794)
						)
					)
					(width 0)
					(fill yes)
				)
			)
		)
		(pad "2" smd custom
			(at 0 0.4445 270)
			(size 0.1397 0.1397)
			(layers "F.Cu" "F.Mask" "F.Paste")
			(net "I2C_IOC_1_SDA")
			(options
				(clearance outline)
				(anchor circle)
			)
			(primitives
				(gr_poly
					(pts
						(arc
							(start -0.1778 -0.2794)
							(mid -0.249642 -0.249642)
							(end -0.2794 -0.1778)
						)
						(arc
							(start -0.2794 0.1778)
							(mid -0.249642 0.249642)
							(end -0.1778 0.2794)
						)
						(arc
							(start 0.1778 0.2794)
							(mid 0.249642 0.249642)
							(end 0.2794 0.1778)
						)
						(arc
							(start 0.2794 -0.1778)
							(mid 0.249642 -0.249642)
							(end 0.1778 -0.2794)
						)
					)
					(width 0)
					(fill yes)
				)
			)
		)
	)
)
